(kicad_pcb
	(version 20260206)
	(generator "pcbnew")
	(generator_version "10.0")
	(general
		(thickness 1.6)
		(legacy_teardrops no)
	)
	(paper "A4")
	(title_block
		(title "04192023_DAF0TMB3IC0_F0TG_MB_C_brd_V02_OCP.brd")
		(comment 1 "Grand Teton / footprints 5658-5665 of 8354")
	)
	(layers
		(0 "F.Cu" signal "TOP")
		(4 "In1.Cu" signal "GND")
		(6 "In2.Cu" signal "IN1")
		(8 "In3.Cu" signal "GND1")
		(10 "In4.Cu" signal "IN2")
		(12 "In5.Cu" signal "GND2")
		(14 "In6.Cu" signal "IN3")
		(16 "In7.Cu" signal "GND3")
		(18 "In8.Cu" signal "VCC")
		(20 "In9.Cu" signal "VCC1")
		(22 "In10.Cu" signal "GND4")
		(24 "In11.Cu" signal "IN4")
		(26 "In12.Cu" signal "GND5")
		(28 "In13.Cu" signal "IN5")
		(30 "In14.Cu" signal "GND6")
		(32 "In15.Cu" signal "IN6")
		(34 "In16.Cu" signal "GND7")
		(2 "B.Cu" signal "BOTTOM")
		(9 "F.Adhes" user "F.Adhesive")
		(11 "B.Adhes" user "B.Adhesive")
		(13 "F.Paste" user "Package Geometry/Pastemask Top")
		(15 "B.Paste" user "Package Geometry/Pastemask Bottom")
		(5 "F.SilkS" user "Ref Des/Silkscreen Top")
		(7 "B.SilkS" user "Ref Des/Silkscreen Bottom")
		(1 "F.Mask" user "Board Geometry/Soldermask Top")
		(3 "B.Mask" user "Board Geometry/Soldermask Bottom")
		(17 "Dwgs.User" user "User.Drawings")
		(19 "Cmts.User" user "User.Comments")
		(21 "Eco1.User" user "User.Eco1")
		(23 "Eco2.User" user "User.Eco2")
		(25 "Edge.Cuts" user "Board Geometry/Outline")
		(27 "Margin" user)
		(31 "F.CrtYd" user "Package Geometry/Place Bound Top")
		(29 "B.CrtYd" user "Package Geometry/Place Bound Bottom")
		(35 "F.Fab" user "Ref Des/Assembly Top")
		(33 "B.Fab" user "Ref Des/Assembly Bottom")
	)
	(footprint ""
		(layer "B.Cu")
		(at 108.355892 -259.845302 180)
		(property "Reference" "C2477"
			(at 0 0 0)
			(layer "B.SilkS")
			(hide yes)
			(effects
				(font
					(size 1.27 1.27)
				)
				(justify mirror)
			)
		)
		(property "Value" ""
			(at 0 0 0)
			(layer "B.Fab")
			(effects
				(font
					(size 1.27 1.27)
				)
				(justify mirror)
			)
		)
		(duplicate_pad_numbers_are_jumpers no)
		(fp_line
			(start 0.7874 0.4064)
			(end 0.7874 -0.4064)
			(stroke
				(width 0.1524)
				(type default)
			)
			(layer "B.SilkS")
		)
		(fp_line
			(start 0.7874 -0.4064)
			(end -0.7874 -0.4064)
			(stroke
				(width 0.1524)
				(type default)
			)
			(layer "B.SilkS")
		)
		(fp_line
			(start -0.7874 0.4064)
			(end 0.7874 0.4064)
			(stroke
				(width 0.1524)
				(type default)
			)
			(layer "B.SilkS")
		)
		(fp_line
			(start -0.7874 -0.4064)
			(end -0.7874 0.4064)
			(stroke
				(width 0.1524)
				(type default)
			)
			(layer "B.SilkS")
		)
		(fp_line
			(start 0.67945 0.3048)
			(end 0.67945 -0.305054)
			(stroke
				(width 0.1)
				(type default)
			)
			(layer "B.Fab")
		)
		(fp_line
			(start 0.67945 -0.305054)
			(end 0.12065 -0.305054)
			(stroke
				(width 0.1)
				(type default)
			)
			(layer "B.Fab")
		)
		(fp_line
			(start 0.12065 0.3048)
			(end 0.67945 0.3048)
			(stroke
				(width 0.1)
				(type default)
			)
			(layer "B.Fab")
		)
		(fp_line
			(start 0.12065 0.2794)
			(end 0.12065 0.3048)
			(stroke
				(width 0.1)
				(type default)
			)
			(layer "B.Fab")
		)
		(fp_line
			(start 0.12065 -0.2794)
			(end -0.12065 -0.2794)
			(stroke
				(width 0.1)
				(type default)
			)
			(layer "B.Fab")
		)
		(fp_line
			(start 0.12065 -0.305054)
			(end 0.12065 -0.2794)
			(stroke
				(width 0.1)
				(type default)
			)
			(layer "B.Fab")
		)
		(fp_line
			(start -0.120396 0.3048)
			(end -0.120396 0.2794)
			(stroke
				(width 0.1)
				(type default)
			)
			(layer "B.Fab")
		)
		(fp_line
			(start -0.120396 0.2794)
			(end 0.12065 0.2794)
			(stroke
				(width 0.1)
				(type default)
			)
			(layer "B.Fab")
		)
		(fp_line
			(start -0.12065 -0.2794)
			(end -0.12065 -0.3048)
			(stroke
				(width 0.1)
				(type default)
			)
			(layer "B.Fab")
		)
		(fp_line
			(start -0.12065 -0.3048)
			(end -0.67945 -0.3048)
			(stroke
				(width 0.1)
				(type default)
			)
			(layer "B.Fab")
		)
		(fp_line
			(start -0.67945 0.3048)
			(end -0.120396 0.3048)
			(stroke
				(width 0.1)
				(type default)
			)
			(layer "B.Fab")
		)
		(fp_line
			(start -0.67945 -0.3048)
			(end -0.67945 0.3048)
			(stroke
				(width 0.1)
				(type default)
			)
			(layer "B.Fab")
		)
		(pad "1" smd circle
			(at 0.40005 0)
			(size 0 0)
			(layers "B.Cu" "B.Mask" "B.Paste")
			(net "PVDDIO_P1")
		)
		(pad "2" smd circle
			(at -0.40005 0)
			(size 0 0)
			(layers "B.Cu" "B.Mask" "B.Paste")
			(net "GND")
		)
	)
	(footprint ""
		(layer "B.Cu")
		(at 88.177878 -148.94941)
		(property "Reference" "R8153"
			(at 0 0 0)
			(layer "B.SilkS")
			(hide yes)
			(effects
				(font
					(size 1.27 1.27)
				)
				(justify mirror)
			)
		)
		(property "Value" ""
			(at 0 0 0)
			(layer "B.Fab")
			(effects
				(font
					(size 1.27 1.27)
				)
				(justify mirror)
			)
		)
		(duplicate_pad_numbers_are_jumpers no)
		(fp_line
			(start -0.7874 -0.4064)
			(end -0.7874 0.4064)
			(stroke
				(width 0.1524)
				(type default)
			)
			(layer "B.SilkS")
		)
		(fp_line
			(start -0.7874 0.4064)
			(end 0.7874 0.4064)
			(stroke
				(width 0.1524)
				(type default)
			)
			(layer "B.SilkS")
		)
		(fp_line
			(start 0.7874 -0.4064)
			(end -0.7874 -0.4064)
			(stroke
				(width 0.1524)
				(type default)
			)
			(layer "B.SilkS")
		)
		(fp_line
			(start 0.7874 0.4064)
			(end 0.7874 -0.4064)
			(stroke
				(width 0.1524)
				(type default)
			)
			(layer "B.SilkS")
		)
		(fp_line
			(start -0.67945 -0.3048)
			(end -0.67945 0.3048)
			(stroke
				(width 0.1)
				(type default)
			)
			(layer "B.Fab")
		)
		(fp_line
			(start -0.67945 0.3048)
			(end -0.120396 0.3048)
			(stroke
				(width 0.1)
				(type default)
			)
			(layer "B.Fab")
		)
		(fp_line
			(start -0.12065 -0.3048)
			(end -0.67945 -0.3048)
			(stroke
				(width 0.1)
				(type default)
			)
			(layer "B.Fab")
		)
		(fp_line
			(start -0.12065 -0.2794)
			(end -0.12065 -0.3048)
			(stroke
				(width 0.1)
				(type default)
			)
			(layer "B.Fab")
		)
		(fp_line
			(start -0.120396 0.2794)
			(end 0.12065 0.2794)
			(stroke
				(width 0.1)
				(type default)
			)
			(layer "B.Fab")
		)
		(fp_line
			(start -0.120396 0.3048)
			(end -0.120396 0.2794)
			(stroke
				(width 0.1)
				(type default)
			)
			(layer "B.Fab")
		)
		(fp_line
			(start 0.12065 -0.305054)
			(end 0.12065 -0.2794)
			(stroke
				(width 0.1)
				(type default)
			)
			(layer "B.Fab")
		)
		(fp_line
			(start 0.12065 -0.2794)
			(end -0.12065 -0.2794)
			(stroke
				(width 0.1)
				(type default)
			)
			(layer "B.Fab")
		)
		(fp_line
			(start 0.12065 0.2794)
			(end 0.12065 0.3048)
			(stroke
				(width 0.1)
				(type default)
			)
			(layer "B.Fab")
		)
		(fp_line
			(start 0.12065 0.3048)
			(end 0.67945 0.3048)
			(stroke
				(width 0.1)
				(type default)
			)
			(layer "B.Fab")
		)
		(fp_line
			(start 0.67945 -0.305054)
			(end 0.12065 -0.305054)
			(stroke
				(width 0.1)
				(type default)
			)
			(layer "B.Fab")
		)
		(fp_line
			(start 0.67945 0.3048)
			(end 0.67945 -0.305054)
			(stroke
				(width 0.1)
				(type default)
			)
			(layer "B.Fab")
		)
		(pad "1" smd circle
			(at 0.40005 0 180)
			(size 0 0)
			(layers "B.Cu" "B.Mask" "B.Paste")
			(net "SVID_PVDDCR_CPU0_P1_SVTO")
		)
		(pad "2" smd circle
			(at -0.40005 0 180)
			(size 0 0)
			(layers "B.Cu" "B.Mask" "B.Paste")
			(net "GND")
		)
	)
	(footprint ""
		(layer "B.Cu")
		(at 280.855928 -338.005928 -90)
		(property "Reference" "PC192_3"
			(at 0 0 90)
			(layer "B.SilkS")
			(hide yes)
			(effects
				(font
					(size 1.27 1.27)
				)
				(justify mirror)
			)
		)
		(property "Value" ""
			(at 0 0 90)
			(layer "B.Fab")
			(effects
				(font
					(size 1.27 1.27)
				)
				(justify mirror)
			)
		)
		(duplicate_pad_numbers_are_jumpers no)
		(fp_line
			(start -1.524 0.762)
			(end 1.524 0.762)
			(stroke
				(width 0.1524)
				(type default)
			)
			(layer "B.SilkS")
		)
		(fp_line
			(start 1.524 0.762)
			(end 1.524 -0.762)
			(stroke
				(width 0.1524)
				(type default)
			)
			(layer "B.SilkS")
		)
		(fp_line
			(start -1.524 -0.762)
			(end -1.524 0.762)
			(stroke
				(width 0.1524)
				(type default)
			)
			(layer "B.SilkS")
		)
		(fp_line
			(start 1.524 -0.762)
			(end -1.524 -0.762)
			(stroke
				(width 0.1524)
				(type default)
			)
			(layer "B.SilkS")
		)
		(fp_line
			(start -1.1049 0.724916)
			(end -1.1049 -0.724916)
			(stroke
				(width 0.1)
				(type default)
			)
			(layer "B.Fab")
		)
		(fp_line
			(start 1.1049 0.724916)
			(end -1.1049 0.724916)
			(stroke
				(width 0.1)
				(type default)
			)
			(layer "B.Fab")
		)
		(fp_line
			(start -1.1049 -0.724916)
			(end 1.1049 -0.724916)
			(stroke
				(width 0.1)
				(type default)
			)
			(layer "B.Fab")
		)
		(fp_line
			(start 1.1049 -0.724916)
			(end 1.1049 0.724916)
			(stroke
				(width 0.1)
				(type default)
			)
			(layer "B.Fab")
		)
		(pad "1" smd rect
			(at 0.889 0 270)
			(size 1.016 1.27)
			(layers "B.Cu" "B.Mask" "B.Paste")
			(net "PVDDIO_P0")
		)
		(pad "2" smd rect
			(at -0.889 0 270)
			(size 1.016 1.27)
			(layers "B.Cu" "B.Mask" "B.Paste")
			(net "GND")
		)
	)
	(footprint ""
		(layer "B.Cu")
		(at 289.891216 -337.984846 -90)
		(property "Reference" "PC170_2"
			(at 0 0 90)
			(layer "B.SilkS")
			(hide yes)
			(effects
				(font
					(size 1.27 1.27)
				)
				(justify mirror)
			)
		)
		(property "Value" ""
			(at 0 0 90)
			(layer "B.Fab")
			(effects
				(font
					(size 1.27 1.27)
				)
				(justify mirror)
			)
		)
		(duplicate_pad_numbers_are_jumpers no)
		(fp_line
			(start -1.524 0.762)
			(end 1.524 0.762)
			(stroke
				(width 0.1524)
				(type default)
			)
			(layer "B.SilkS")
		)
		(fp_line
			(start 1.524 0.762)
			(end 1.524 -0.762)
			(stroke
				(width 0.1524)
				(type default)
			)
			(layer "B.SilkS")
		)
		(fp_line
			(start -1.524 -0.762)
			(end -1.524 0.762)
			(stroke
				(width 0.1524)
				(type default)
			)
			(layer "B.SilkS")
		)
		(fp_line
			(start 1.524 -0.762)
			(end -1.524 -0.762)
			(stroke
				(width 0.1524)
				(type default)
			)
			(layer "B.SilkS")
		)
		(fp_line
			(start -1.1049 0.724916)
			(end -1.1049 -0.724916)
			(stroke
				(width 0.1)
				(type default)
			)
			(layer "B.Fab")
		)
		(fp_line
			(start 1.1049 0.724916)
			(end -1.1049 0.724916)
			(stroke
				(width 0.1)
				(type default)
			)
			(layer "B.Fab")
		)
		(fp_line
			(start -1.1049 -0.724916)
			(end 1.1049 -0.724916)
			(stroke
				(width 0.1)
				(type default)
			)
			(layer "B.Fab")
		)
		(fp_line
			(start 1.1049 -0.724916)
			(end 1.1049 0.724916)
			(stroke
				(width 0.1)
				(type default)
			)
			(layer "B.Fab")
		)
		(pad "1" smd rect
			(at 0.889 0 270)
			(size 1.016 1.27)
			(layers "B.Cu" "B.Mask" "B.Paste")
			(net "PVDDIO_P0")
		)
		(pad "2" smd rect
			(at -0.889 0 270)
			(size 1.016 1.27)
			(layers "B.Cu" "B.Mask" "B.Paste")
			(net "GND")
		)
	)
	(footprint ""
		(layer "B.Cu")
		(at 164.363908 -113.013744)
		(property "Reference" "R6145"
			(at 0 0 0)
			(layer "B.SilkS")
			(hide yes)
			(effects
				(font
					(size 1.27 1.27)
				)
				(justify mirror)
			)
		)
		(property "Value" ""
			(at 0 0 0)
			(layer "B.Fab")
			(effects
				(font
					(size 1.27 1.27)
				)
				(justify mirror)
			)
		)
		(duplicate_pad_numbers_are_jumpers no)
		(fp_line
			(start -0.7874 -0.4064)
			(end -0.7874 0.4064)
			(stroke
				(width 0.1524)
				(type default)
			)
			(layer "B.SilkS")
		)
		(fp_line
			(start -0.7874 0.4064)
			(end 0.7874 0.4064)
			(stroke
				(width 0.1524)
				(type default)
			)
			(layer "B.SilkS")
		)
		(fp_line
			(start 0.7874 -0.4064)
			(end -0.7874 -0.4064)
			(stroke
				(width 0.1524)
				(type default)
			)
			(layer "B.SilkS")
		)
		(fp_line
			(start 0.7874 0.4064)
			(end 0.7874 -0.4064)
			(stroke
				(width 0.1524)
				(type default)
			)
			(layer "B.SilkS")
		)
		(fp_line
			(start -0.67945 -0.3048)
			(end -0.67945 0.3048)
			(stroke
				(width 0.1)
				(type default)
			)
			(layer "B.Fab")
		)
		(fp_line
			(start -0.67945 0.3048)
			(end -0.120396 0.3048)
			(stroke
				(width 0.1)
				(type default)
			)
			(layer "B.Fab")
		)
		(fp_line
			(start -0.12065 -0.3048)
			(end -0.67945 -0.3048)
			(stroke
				(width 0.1)
				(type default)
			)
			(layer "B.Fab")
		)
		(fp_line
			(start -0.12065 -0.2794)
			(end -0.12065 -0.3048)
			(stroke
				(width 0.1)
				(type default)
			)
			(layer "B.Fab")
		)
		(fp_line
			(start -0.120396 0.2794)
			(end 0.12065 0.2794)
			(stroke
				(width 0.1)
				(type default)
			)
			(layer "B.Fab")
		)
		(fp_line
			(start -0.120396 0.3048)
			(end -0.120396 0.2794)
			(stroke
				(width 0.1)
				(type default)
			)
			(layer "B.Fab")
		)
		(fp_line
			(start 0.12065 -0.305054)
			(end 0.12065 -0.2794)
			(stroke
				(width 0.1)
				(type default)
			)
			(layer "B.Fab")
		)
		(fp_line
			(start 0.12065 -0.2794)
			(end -0.12065 -0.2794)
			(stroke
				(width 0.1)
				(type default)
			)
			(layer "B.Fab")
		)
		(fp_line
			(start 0.12065 0.2794)
			(end 0.12065 0.3048)
			(stroke
				(width 0.1)
				(type default)
			)
			(layer "B.Fab")
		)
		(fp_line
			(start 0.12065 0.3048)
			(end 0.67945 0.3048)
			(stroke
				(width 0.1)
				(type default)
			)
			(layer "B.Fab")
		)
		(fp_line
			(start 0.67945 -0.305054)
			(end 0.12065 -0.305054)
			(stroke
				(width 0.1)
				(type default)
			)
			(layer "B.Fab")
		)
		(fp_line
			(start 0.67945 0.3048)
			(end 0.67945 -0.305054)
			(stroke
				(width 0.1)
				(type default)
			)
			(layer "B.Fab")
		)
		(pad "1" smd circle
			(at 0.40005 0 180)
			(size 0 0)
			(layers "B.Cu" "B.Mask" "B.Paste")
			(net "FM_BOARD_BMC_SKU_ID0")
		)
		(pad "2" smd circle
			(at -0.40005 0 180)
			(size 0 0)
			(layers "B.Cu" "B.Mask" "B.Paste")
			(net "GND")
		)
	)
	(footprint ""
		(layer "B.Cu")
		(at 40.240204 -192.66027 180)
		(property "Reference" "C178"
			(at 0 0 0)
			(layer "B.SilkS")
			(hide yes)
			(effects
				(font
					(size 1.27 1.27)
				)
				(justify mirror)
			)
		)
		(property "Value" ""
			(at 0 0 0)
			(layer "B.Fab")
			(effects
				(font
					(size 1.27 1.27)
				)
				(justify mirror)
			)
		)
		(duplicate_pad_numbers_are_jumpers no)
		(fp_line
			(start 1.524 0.762)
			(end 1.524 -0.762)
			(stroke
				(width 0.1524)
				(type default)
			)
			(layer "B.SilkS")
		)
		(fp_line
			(start 1.524 -0.762)
			(end -1.524 -0.762)
			(stroke
				(width 0.1524)
				(type default)
			)
			(layer "B.SilkS")
		)
		(fp_line
			(start -1.524 0.762)
			(end 1.524 0.762)
			(stroke
				(width 0.1524)
				(type default)
			)
			(layer "B.SilkS")
		)
		(fp_line
			(start -1.524 -0.762)
			(end -1.524 0.762)
			(stroke
				(width 0.1524)
				(type default)
			)
			(layer "B.SilkS")
		)
		(fp_line
			(start 1.1049 0.724916)
			(end -1.1049 0.724916)
			(stroke
				(width 0.1)
				(type default)
			)
			(layer "B.Fab")
		)
		(fp_line
			(start 1.1049 -0.724916)
			(end 1.1049 0.724916)
			(stroke
				(width 0.1)
				(type default)
			)
			(layer "B.Fab")
		)
		(fp_line
			(start -1.1049 0.724916)
			(end -1.1049 -0.724916)
			(stroke
				(width 0.1)
				(type default)
			)
			(layer "B.Fab")
		)
		(fp_line
			(start -1.1049 -0.724916)
			(end 1.1049 -0.724916)
			(stroke
				(width 0.1)
				(type default)
			)
			(layer "B.Fab")
		)
		(pad "1" smd rect
			(at 0.889 0 180)
			(size 1.016 1.27)
			(layers "B.Cu" "B.Mask" "B.Paste")
			(net "P12V_MEM_CPU1")
		)
		(pad "2" smd rect
			(at -0.889 0 180)
			(size 1.016 1.27)
			(layers "B.Cu" "B.Mask" "B.Paste")
			(net "GND")
		)
	)
	(footprint ""
		(layer "B.Cu")
		(at 103.173276 -387.084062 -90)
		(property "Reference" "C102"
			(at 0 0 90)
			(layer "B.SilkS")
			(hide yes)
			(effects
				(font
					(size 1.27 1.27)
				)
				(justify mirror)
			)
		)
		(property "Value" ""
			(at 0 0 90)
			(layer "B.Fab")
			(effects
				(font
					(size 1.27 1.27)
				)
				(justify mirror)
			)
		)
		(duplicate_pad_numbers_are_jumpers no)
		(fp_line
			(start -1.524 0.762)
			(end 1.524 0.762)
			(stroke
				(width 0.1524)
				(type default)
			)
			(layer "B.SilkS")
		)
		(fp_line
			(start 1.524 0.762)
			(end 1.524 -0.762)
			(stroke
				(width 0.1524)
				(type default)
			)
			(layer "B.SilkS")
		)
		(fp_line
			(start -1.524 -0.762)
			(end -1.524 0.762)
			(stroke
				(width 0.1524)
				(type default)
			)
			(layer "B.SilkS")
		)
		(fp_line
			(start 1.524 -0.762)
			(end -1.524 -0.762)
			(stroke
				(width 0.1524)
				(type default)
			)
			(layer "B.SilkS")
		)
		(fp_line
			(start -1.1049 0.724916)
			(end -1.1049 -0.724916)
			(stroke
				(width 0.1)
				(type default)
			)
			(layer "B.Fab")
		)
		(fp_line
			(start 1.1049 0.724916)
			(end -1.1049 0.724916)
			(stroke
				(width 0.1)
				(type default)
			)
			(layer "B.Fab")
		)
		(fp_line
			(start -1.1049 -0.724916)
			(end 1.1049 -0.724916)
			(stroke
				(width 0.1)
				(type default)
			)
			(layer "B.Fab")
		)
		(fp_line
			(start 1.1049 -0.724916)
			(end 1.1049 0.724916)
			(stroke
				(width 0.1)
				(type default)
			)
			(layer "B.Fab")
		)
		(pad "1" smd rect
			(at 0.889 0 270)
			(size 1.016 1.27)
			(layers "B.Cu" "B.Mask" "B.Paste")
			(net "P1V8_CPU1_RT_1D")
		)
		(pad "2" smd rect
			(at -0.889 0 270)
			(size 1.016 1.27)
			(layers "B.Cu" "B.Mask" "B.Paste")
			(net "GND")
		)
	)
	(footprint ""
		(layer "B.Cu")
		(at 54.665118 -350.660716 -90)
		(property "Reference" "PC442_1"
			(at 0 0 90)
			(layer "B.SilkS")
			(hide yes)
			(effects
				(font
					(size 1.27 1.27)
				)
				(justify mirror)
			)
		)
		(property "Value" ""
			(at 0 0 90)
			(layer "B.Fab")
			(effects
				(font
					(size 1.27 1.27)
				)
				(justify mirror)
			)
		)
		(duplicate_pad_numbers_are_jumpers no)
		(fp_line
			(start -1.524 0.762)
			(end 1.524 0.762)
			(stroke
				(width 0.1524)
				(type default)
			)
			(layer "B.SilkS")
		)
		(fp_line
			(start 1.524 0.762)
			(end 1.524 -0.762)
			(stroke
				(width 0.1524)
				(type default)
			)
			(layer "B.SilkS")
		)
		(fp_line
			(start -1.524 -0.762)
			(end -1.524 0.762)
			(stroke
				(width 0.1524)
				(type default)
			)
			(layer "B.SilkS")
		)
		(fp_line
			(start 1.524 -0.762)
			(end -1.524 -0.762)
			(stroke
				(width 0.1524)
				(type default)
			)
			(layer "B.SilkS")
		)
		(fp_line
			(start -1.1049 0.724916)
			(end -1.1049 -0.724916)
			(stroke
				(width 0.1)
				(type default)
			)
			(layer "B.Fab")
		)
		(fp_line
			(start 1.1049 0.724916)
			(end -1.1049 0.724916)
			(stroke
				(width 0.1)
				(type default)
			)
			(layer "B.Fab")
		)
		(fp_line
			(start -1.1049 -0.724916)
			(end 1.1049 -0.724916)
			(stroke
				(width 0.1)
				(type default)
			)
			(layer "B.Fab")
		)
		(fp_line
			(start 1.1049 -0.724916)
			(end 1.1049 0.724916)
			(stroke
				(width 0.1)
				(type default)
			)
			(layer "B.Fab")
		)
		(pad "1" smd rect
			(at 0.889 0 270)
			(size 1.016 1.27)
			(layers "B.Cu" "B.Mask" "B.Paste")
			(net "SW_P12V_AUX_PVDDIO_P1_FLT")
		)
		(pad "2" smd rect
			(at -0.889 0 270)
			(size 1.016 1.27)
			(layers "B.Cu" "B.Mask" "B.Paste")
			(net "GND")
		)
	)
)
